(kicad_pcb
	(version 20260206)
	(generator "pcbnew")
	(generator_version "10.0")
	(general
		(thickness 1.6)
		(legacy_teardrops no)
	)
	(paper "A4")
	(title_block
		(title "baseboard — 13948-1b.1110WZS1818.brd")
		(comment 1 "Honey Badger (Wiwynn) / footprints 2027-2036 of 2523")
	)
	(layers
		(0 "F.Cu" signal "TOP")
		(4 "In1.Cu" signal "L2GND")
		(6 "In2.Cu" signal "L3")
		(8 "In3.Cu" signal "L4VCC")
		(10 "In4.Cu" signal "L5VCC")
		(12 "In5.Cu" signal "L6")
		(14 "In6.Cu" signal "L7GND")
		(2 "B.Cu" signal "BOTTOM")
		(9 "F.Adhes" user "F.Adhesive")
		(11 "B.Adhes" user "B.Adhesive")
		(13 "F.Paste" user "Package Geometry/Pastemask Top")
		(15 "B.Paste" user "Package Geometry/Pastemask Bottom")
		(5 "F.SilkS" user "Ref Des/Silkscreen Top")
		(7 "B.SilkS" user "Ref Des/Silkscreen Bottom")
		(1 "F.Mask" user "Board Geometry/Soldermask Top")
		(3 "B.Mask" user "Board Geometry/Soldermask Bottom")
		(17 "Dwgs.User" user "User.Drawings")
		(19 "Cmts.User" user "User.Comments")
		(21 "Eco1.User" user "User.Eco1")
		(23 "Eco2.User" user "User.Eco2")
		(25 "Edge.Cuts" user "Board Geometry/Outline")
		(27 "Margin" user)
		(31 "F.CrtYd" user "Package Geometry/Place Bound Top")
		(29 "B.CrtYd" user "Package Geometry/Place Bound Bottom")
		(35 "F.Fab" user "Ref Des/Assembly Top")
		(33 "B.Fab" user "Ref Des/Assembly Bottom")
	)
	(footprint ""
		(layer "B.Cu")
		(at 78.220062 -62.700408 180)
		(property "Reference" "SL4"
			(at 0 0 0)
			(layer "B.SilkS")
			(hide yes)
			(effects
				(font
					(size 1.27 1.27)
				)
				(justify mirror)
			)
		)
		(property "Value" "MPZ2012S601AT-GP"
			(at 0 -4.2418 180)
			(unlocked yes)
			(layer "B.Fab")
			(hide yes)
			(effects
				(font
					(size 1.016 1.016)
					(thickness 0.1524)
				)
				(justify mirror)
			)
		)
		(property "Device Type" "L805H42"
			(at 0 -5.7912 180)
			(unlocked yes)
			(layer "B.Fab")
			(hide yes)
			(effects
				(font
					(size 1.016 1.016)
					(thickness 0.1524)
				)
				(justify mirror)
			)
		)
		(duplicate_pad_numbers_are_jumpers no)
		(fp_line
			(start 0.889 1.7018)
			(end 0.889 -1.7018)
			(stroke
				(width 0.1524)
				(type default)
			)
			(layer "B.SilkS")
		)
		(fp_line
			(start 0.889 -1.7018)
			(end -0.889 -1.7018)
			(stroke
				(width 0.1524)
				(type default)
			)
			(layer "B.SilkS")
		)
		(fp_line
			(start -0.889 1.7018)
			(end 0.889 1.7018)
			(stroke
				(width 0.1524)
				(type default)
			)
			(layer "B.SilkS")
		)
		(fp_line
			(start -0.889 -1.7018)
			(end -0.889 1.7018)
			(stroke
				(width 0.1524)
				(type default)
			)
			(layer "B.SilkS")
		)
		(fp_rect
			(start 0.9652 1.778)
			(end -0.9652 -1.778)
			(stroke
				(width 0)
				(type default)
			)
			(fill no)
			(layer "B.CrtYd")
		)
		(fp_rect
			(start 0.9652 1.778)
			(end -0.9652 -1.778)
			(stroke
				(width 0)
				(type default)
			)
			(fill no)
			(layer "B.Fab")
		)
		(pad "1" smd rect
			(at 0 -0.9652)
			(size 1.397 1.143)
			(layers "B.Cu" "B.Mask" "B.Paste")
			(net "VDDA_SAS_REF_CLK")
		)
		(pad "2" smd rect
			(at 0 0.9652)
			(size 1.397 1.143)
			(layers "B.Cu" "B.Mask" "B.Paste")
			(net "P1V8_C")
		)
	)
	(footprint ""
		(layer "B.Cu")
		(at 94.294706 -48.30318)
		(property "Reference" "SC1013"
			(at 0 0 0)
			(layer "B.SilkS")
			(hide yes)
			(effects
				(font
					(size 1.27 1.27)
				)
				(justify mirror)
			)
		)
		(property "Value" "SC1KP50V2KX-1GP"
			(at -1.1811 -2.7051 0)
			(unlocked yes)
			(layer "B.Fab")
			(hide yes)
			(effects
				(font
					(size 1.016 1.016)
					(thickness 0.1524)
				)
				(justify mirror)
			)
		)
		(property "Device Type" "C402H22"
			(at -1.1811 -4.2291 0)
			(unlocked yes)
			(layer "B.Fab")
			(hide yes)
			(effects
				(font
					(size 1.016 1.016)
					(thickness 0.1524)
				)
				(justify mirror)
			)
		)
		(duplicate_pad_numbers_are_jumpers no)
		(fp_rect
			(start 0.4318 0.9525)
			(end -0.4318 -0.9525)
			(stroke
				(width 0)
				(type default)
			)
			(fill no)
			(layer "B.CrtYd")
		)
		(fp_rect
			(start 0.4318 0.9525)
			(end -0.4318 -0.9525)
			(stroke
				(width 0)
				(type default)
			)
			(fill no)
			(layer "B.Fab")
		)
		(pad "1" smd custom
			(at 0 -0.4445 180)
			(size 0.1524 0.1524)
			(layers "B.Cu" "B.Mask" "B.Paste")
			(net "P1V8_C")
			(options
				(clearance outline)
				(anchor circle)
			)
			(primitives
				(gr_poly
					(pts
						(arc
							(start 0.3048 0.2032)
							(mid 0.275042 0.275042)
							(end 0.2032 0.3048)
						)
						(arc
							(start -0.2032 0.3048)
							(mid -0.275042 0.275042)
							(end -0.3048 0.2032)
						)
						(arc
							(start -0.3048 -0.2032)
							(mid -0.275042 -0.275042)
							(end -0.2032 -0.3048)
						)
						(arc
							(start 0.2032 -0.3048)
							(mid 0.275042 -0.275042)
							(end 0.3048 -0.2032)
						)
					)
					(width 0)
					(fill yes)
				)
			)
		)
		(pad "2" smd custom
			(at 0 0.4445 180)
			(size 0.1524 0.1524)
			(layers "B.Cu" "B.Mask" "B.Paste")
			(net "GND")
			(options
				(clearance outline)
				(anchor circle)
			)
			(primitives
				(gr_poly
					(pts
						(arc
							(start 0.3048 0.2032)
							(mid 0.275042 0.275042)
							(end 0.2032 0.3048)
						)
						(arc
							(start -0.2032 0.3048)
							(mid -0.275042 0.275042)
							(end -0.3048 0.2032)
						)
						(arc
							(start -0.3048 -0.2032)
							(mid -0.275042 -0.275042)
							(end -0.2032 -0.3048)
						)
						(arc
							(start 0.2032 -0.3048)
							(mid 0.275042 -0.275042)
							(end 0.3048 -0.2032)
						)
					)
					(width 0)
					(fill yes)
				)
			)
		)
	)
	(footprint ""
		(layer "B.Cu")
		(at 101.48697 -109.982 180)
		(property "Reference" "SR746"
			(at 0 0 0)
			(layer "B.SilkS")
			(hide yes)
			(effects
				(font
					(size 1.27 1.27)
				)
				(justify mirror)
			)
		)
		(property "Value" "4K7R2F-GP"
			(at -0.064008 -3.993896 180)
			(unlocked yes)
			(layer "B.Fab")
			(hide yes)
			(effects
				(font
					(size 1.016 1.016)
					(thickness 0.1524)
				)
				(justify mirror)
			)
		)
		(property "Device Type" "R402H16"
			(at -0.064008 -5.517896 180)
			(unlocked yes)
			(layer "B.Fab")
			(hide yes)
			(effects
				(font
					(size 1.016 1.016)
					(thickness 0.1524)
				)
				(justify mirror)
			)
		)
		(duplicate_pad_numbers_are_jumpers no)
		(fp_line
			(start 0.508 -0.9398)
			(end 0.508 0.9398)
			(stroke
				(width 0.1524)
				(type default)
			)
			(layer "B.SilkS")
		)
		(fp_line
			(start -0.508 -0.9398)
			(end 0.508 -0.9398)
			(stroke
				(width 0.1524)
				(type default)
			)
			(layer "B.SilkS")
		)
		(fp_rect
			(start 0.508 0.9398)
			(end -0.508 -0.9398)
			(stroke
				(width 0)
				(type default)
			)
			(fill no)
			(layer "B.CrtYd")
		)
		(fp_rect
			(start 0.508 0.9398)
			(end -0.508 -0.9398)
			(stroke
				(width 0)
				(type default)
			)
			(fill no)
			(layer "B.Fab")
		)
		(pad "1" smd custom
			(at 0 -0.4445)
			(size 0.1397 0.1397)
			(layers "B.Cu" "B.Mask" "B.Paste")
			(net "EXP_SIO_CLK_OUT")
			(options
				(clearance outline)
				(anchor circle)
			)
			(primitives
				(gr_poly
					(pts
						(arc
							(start -0.1778 0.2794)
							(mid -0.249642 0.249642)
							(end -0.2794 0.1778)
						)
						(arc
							(start -0.2794 -0.1778)
							(mid -0.249642 -0.249642)
							(end -0.1778 -0.2794)
						)
						(arc
							(start 0.1778 -0.2794)
							(mid 0.249642 -0.249642)
							(end 0.2794 -0.1778)
						)
						(arc
							(start 0.2794 0.1778)
							(mid 0.249642 0.249642)
							(end 0.1778 0.2794)
						)
					)
					(width 0)
					(fill yes)
				)
			)
		)
		(pad "2" smd custom
			(at 0 0.4445)
			(size 0.1397 0.1397)
			(layers "B.Cu" "B.Mask" "B.Paste")
			(net "P1V8_E")
			(options
				(clearance outline)
				(anchor circle)
			)
			(primitives
				(gr_poly
					(pts
						(arc
							(start -0.1778 0.2794)
							(mid -0.249642 0.249642)
							(end -0.2794 0.1778)
						)
						(arc
							(start -0.2794 -0.1778)
							(mid -0.249642 -0.249642)
							(end -0.1778 -0.2794)
						)
						(arc
							(start 0.1778 -0.2794)
							(mid 0.249642 -0.249642)
							(end 0.2794 -0.1778)
						)
						(arc
							(start 0.2794 0.1778)
							(mid 0.249642 0.249642)
							(end 0.1778 0.2794)
						)
					)
					(width 0)
					(fill yes)
				)
			)
		)
	)
	(footprint ""
		(layer "B.Cu")
		(at 120.142 -40.005 -90)
		(property "Reference" "SR619"
			(at 0 0 90)
			(layer "B.SilkS")
			(hide yes)
			(effects
				(font
					(size 1.27 1.27)
				)
				(justify mirror)
			)
		)
		(property "Value" "2K2R2F-GP"
			(at -0.064008 -3.993896 270)
			(unlocked yes)
			(layer "B.Fab")
			(hide yes)
			(effects
				(font
					(size 1.016 1.016)
					(thickness 0.1524)
				)
				(justify mirror)
			)
		)
		(property "Device Type" "R402H16"
			(at -0.064008 -5.517896 270)
			(unlocked yes)
			(layer "B.Fab")
			(hide yes)
			(effects
				(font
					(size 1.016 1.016)
					(thickness 0.1524)
				)
				(justify mirror)
			)
		)
		(duplicate_pad_numbers_are_jumpers no)
		(fp_line
			(start -0.508 -0.9398)
			(end 0.508 -0.9398)
			(stroke
				(width 0.1524)
				(type default)
			)
			(layer "B.SilkS")
		)
		(fp_line
			(start 0.508 -0.9398)
			(end 0.508 0.9398)
			(stroke
				(width 0.1524)
				(type default)
			)
			(layer "B.SilkS")
		)
		(fp_rect
			(start 0.508 0.9398)
			(end -0.508 -0.9398)
			(stroke
				(width 0)
				(type default)
			)
			(fill no)
			(layer "B.CrtYd")
		)
		(fp_rect
			(start 0.508 0.9398)
			(end -0.508 -0.9398)
			(stroke
				(width 0)
				(type default)
			)
			(fill no)
			(layer "B.Fab")
		)
		(pad "1" smd custom
			(at 0 -0.4445 90)
			(size 0.1397 0.1397)
			(layers "B.Cu" "B.Mask" "B.Paste")
			(net "P1V8_C")
			(options
				(clearance outline)
				(anchor circle)
			)
			(primitives
				(gr_poly
					(pts
						(arc
							(start -0.1778 0.2794)
							(mid -0.249642 0.249642)
							(end -0.2794 0.1778)
						)
						(arc
							(start -0.2794 -0.1778)
							(mid -0.249642 -0.249642)
							(end -0.1778 -0.2794)
						)
						(arc
							(start 0.1778 -0.2794)
							(mid 0.249642 -0.249642)
							(end 0.2794 -0.1778)
						)
						(arc
							(start 0.2794 0.1778)
							(mid 0.249642 0.249642)
							(end 0.1778 0.2794)
						)
					)
					(width 0)
					(fill yes)
				)
			)
		)
		(pad "2" smd custom
			(at 0 0.4445 90)
			(size 0.1397 0.1397)
			(layers "B.Cu" "B.Mask" "B.Paste")
			(net "IOC_SDA_1")
			(options
				(clearance outline)
				(anchor circle)
			)
			(primitives
				(gr_poly
					(pts
						(arc
							(start -0.1778 0.2794)
							(mid -0.249642 0.249642)
							(end -0.2794 0.1778)
						)
						(arc
							(start -0.2794 -0.1778)
							(mid -0.249642 -0.249642)
							(end -0.1778 -0.2794)
						)
						(arc
							(start 0.1778 -0.2794)
							(mid 0.249642 -0.249642)
							(end 0.2794 -0.1778)
						)
						(arc
							(start 0.2794 0.1778)
							(mid 0.249642 0.249642)
							(end 0.1778 0.2794)
						)
					)
					(width 0)
					(fill yes)
				)
			)
		)
	)
	(footprint ""
		(layer "B.Cu")
		(at 284.92704 -169.07256)
		(property "Reference" "TP163"
			(at 0 0 0)
			(layer "B.SilkS")
			(hide yes)
			(effects
				(font
					(size 1.27 1.27)
				)
				(justify mirror)
			)
		)
		(property "Value" "TPAD28"
			(at -0.0127 -1.8034 0)
			(unlocked yes)
			(layer "B.Fab")
			(hide yes)
			(effects
				(font
					(size 1.016 1.016)
					(thickness 0.1524)
				)
				(justify mirror)
			)
		)
		(property "Device Type" "TPAD28"
			(at -0.0127 -3.3274 0)
			(unlocked yes)
			(layer "B.Fab")
			(hide yes)
			(effects
				(font
					(size 1.016 1.016)
					(thickness 0.1524)
				)
				(justify mirror)
			)
		)
		(duplicate_pad_numbers_are_jumpers no)
		(fp_poly
			(pts
				(arc
					(start 0.3556 0)
					(mid -0.3556 0)
					(end 0.3556 0)
				)
			)
			(stroke
				(width 0)
				(type default)
			)
			(fill no)
			(layer "B.CrtYd")
		)
		(fp_poly
			(pts
				(arc
					(start 0.6096 0)
					(mid -0.6096 0)
					(end 0.6096 0)
				)
			)
			(stroke
				(width 0)
				(type default)
			)
			(fill no)
			(layer "B.Fab")
		)
		(pad "1" smd circle
			(at 0 0 180)
			(size 0.7112 0.7112)
			(layers "B.Cu" "B.Mask" "B.Paste")
			(net "TP_BMC_GPIOB7")
		)
	)
	(footprint ""
		(layer "B.Cu")
		(at 95.53956 -47.4472)
		(property "Reference" "STP29"
			(at 0 0 0)
			(layer "B.SilkS")
			(hide yes)
			(effects
				(font
					(size 1.27 1.27)
				)
				(justify mirror)
			)
		)
		(property "Value" "TPAD28"
			(at -0.0127 -1.8034 0)
			(unlocked yes)
			(layer "B.Fab")
			(hide yes)
			(effects
				(font
					(size 1.016 1.016)
					(thickness 0.1524)
				)
				(justify mirror)
			)
		)
		(property "Device Type" "TPAD28"
			(at -0.0127 -3.3274 0)
			(unlocked yes)
			(layer "B.Fab")
			(hide yes)
			(effects
				(font
					(size 1.016 1.016)
					(thickness 0.1524)
				)
				(justify mirror)
			)
		)
		(duplicate_pad_numbers_are_jumpers no)
		(fp_poly
			(pts
				(arc
					(start 0.3556 0)
					(mid -0.3556 0)
					(end 0.3556 0)
				)
			)
			(stroke
				(width 0)
				(type default)
			)
			(fill no)
			(layer "B.CrtYd")
		)
		(fp_poly
			(pts
				(arc
					(start 0.6096 0)
					(mid -0.6096 0)
					(end 0.6096 0)
				)
			)
			(stroke
				(width 0)
				(type default)
			)
			(fill no)
			(layer "B.Fab")
		)
		(pad "1" smd circle
			(at 0 0 180)
			(size 0.7112 0.7112)
			(layers "B.Cu" "B.Mask" "B.Paste")
			(net "ICE_SEL")
		)
	)
	(footprint ""
		(layer "B.Cu")
		(at 97.9932 -52.559966 -90)
		(property "Reference" "SC1022"
			(at 0 0 90)
			(layer "B.SilkS")
			(hide yes)
			(effects
				(font
					(size 1.27 1.27)
				)
				(justify mirror)
			)
		)
		(property "Value" "SC10U6D3V5KX-4GP"
			(at 0.0762 -6.1214 270)
			(unlocked yes)
			(layer "B.Fab")
			(hide yes)
			(effects
				(font
					(size 1.016 1.016)
					(thickness 0.1524)
				)
				(justify mirror)
			)
		)
		(property "Device Type" "C805H58"
			(at 0.0762 -8.1534 270)
			(unlocked yes)
			(layer "B.Fab")
			(hide yes)
			(effects
				(font
					(size 1.016 1.016)
					(thickness 0.1524)
				)
				(justify mirror)
			)
		)
		(duplicate_pad_numbers_are_jumpers no)
		(fp_line
			(start -0.635 0)
			(end 0.635 0)
			(stroke
				(width 0.508)
				(type default)
			)
			(layer "B.SilkS")
		)
		(fp_rect
			(start 0.9652 1.778)
			(end -0.9652 -1.778)
			(stroke
				(width 0)
				(type default)
			)
			(fill no)
			(layer "B.CrtYd")
		)
		(fp_poly
			(pts
				(xy 0.9652 -1.778) (xy -0.9652 -1.778) (xy -0.9652 1.778) (xy 0.9652 1.778)
			)
			(stroke
				(width 0)
				(type default)
			)
			(fill no)
			(layer "B.Fab")
		)
		(pad "1" smd rect
			(at 0 -0.9652 90)
			(size 1.397 1.143)
			(layers "B.Cu" "B.Mask" "B.Paste")
			(net "P0V955_C")
		)
		(pad "2" smd rect
			(at 0 0.9652 90)
			(size 1.397 1.143)
			(layers "B.Cu" "B.Mask" "B.Paste")
			(net "GND")
		)
	)
	(footprint ""
		(layer "B.Cu")
		(at 115.17757 -101.3968 180)
		(property "Reference" "SC1138"
			(at 0 0 0)
			(layer "B.SilkS")
			(hide yes)
			(effects
				(font
					(size 1.27 1.27)
				)
				(justify mirror)
			)
		)
		(property "Value" "SCD1U6D3V1KX-GP"
			(at 2.8321 -1.7399 180)
			(unlocked yes)
			(layer "B.Fab")
			(hide yes)
			(effects
				(font
					(size 1.016 1.016)
					(thickness 0.1524)
				)
				(justify mirror)
			)
		)
		(property "Device Type" "C0201H13"
			(at 2.8321 -3.2639 180)
			(unlocked yes)
			(layer "B.Fab")
			(hide yes)
			(effects
				(font
					(size 1.016 1.016)
					(thickness 0.1524)
				)
				(justify mirror)
			)
		)
		(duplicate_pad_numbers_are_jumpers no)
		(fp_rect
			(start 0.2794 0.6477)
			(end -0.2794 -0.6477)
			(stroke
				(width 0)
				(type default)
			)
			(fill no)
			(layer "B.CrtYd")
		)
		(fp_rect
			(start 0.2794 0.6477)
			(end -0.2794 -0.6477)
			(stroke
				(width 0)
				(type default)
			)
			(fill no)
			(layer "B.Fab")
		)
		(pad "1" smd custom
			(at 0 -0.2794)
			(size 0.0762 0.0762)
			(layers "B.Cu" "B.Mask" "B.Paste")
			(net "GB_VDDH2")
			(options
				(clearance outline)
				(anchor circle)
			)
			(primitives
				(gr_poly
					(pts
						(arc
							(start 0.1524 0.127)
							(mid 0.137521 0.162921)
							(end 0.1016 0.1778)
						)
						(arc
							(start -0.1016 0.1778)
							(mid -0.137521 0.162921)
							(end -0.1524 0.127)
						)
						(arc
							(start -0.1524 -0.127)
							(mid -0.137521 -0.162921)
							(end -0.1016 -0.1778)
						)
						(arc
							(start 0.1016 -0.1778)
							(mid 0.137521 -0.162921)
							(end 0.1524 -0.127)
						)
					)
					(width 0)
					(fill yes)
				)
			)
		)
		(pad "2" smd custom
			(at 0 0.2794)
			(size 0.0762 0.0762)
			(layers "B.Cu" "B.Mask" "B.Paste")
			(net "GND")
			(options
				(clearance outline)
				(anchor circle)
			)
			(primitives
				(gr_poly
					(pts
						(arc
							(start 0.1524 0.127)
							(mid 0.137521 0.162921)
							(end 0.1016 0.1778)
						)
						(arc
							(start -0.1016 0.1778)
							(mid -0.137521 0.162921)
							(end -0.1524 0.127)
						)
						(arc
							(start -0.1524 -0.127)
							(mid -0.137521 -0.162921)
							(end -0.1016 -0.1778)
						)
						(arc
							(start 0.1016 -0.1778)
							(mid 0.137521 -0.162921)
							(end 0.1524 -0.127)
						)
					)
					(width 0)
					(fill yes)
				)
			)
		)
	)
	(footprint ""
		(layer "B.Cu")
		(at 18.238216 -216.71788 90)
		(property "Reference" "SC428"
			(at 0 0 90)
			(layer "B.SilkS")
			(hide yes)
			(effects
				(font
					(size 1.27 1.27)
				)
				(justify mirror)
			)
		)
		(property "Value" "SCD1U16V2KX-3GP"
			(at -1.1811 -2.7051 90)
			(unlocked yes)
			(layer "B.Fab")
			(hide yes)
			(effects
				(font
					(size 1.016 1.016)
					(thickness 0.1524)
				)
				(justify mirror)
			)
		)
		(property "Device Type" "C402H22"
			(at -1.1811 -4.2291 90)
			(unlocked yes)
			(layer "B.Fab")
			(hide yes)
			(effects
				(font
					(size 1.016 1.016)
					(thickness 0.1524)
				)
				(justify mirror)
			)
		)
		(duplicate_pad_numbers_are_jumpers no)
		(fp_rect
			(start 0.4318 0.9525)
			(end -0.4318 -0.9525)
			(stroke
				(width 0)
				(type default)
			)
			(fill no)
			(layer "B.CrtYd")
		)
		(fp_rect
			(start 0.4318 0.9525)
			(end -0.4318 -0.9525)
			(stroke
				(width 0)
				(type default)
			)
			(fill no)
			(layer "B.Fab")
		)
		(pad "1" smd custom
			(at 0 -0.4445 270)
			(size 0.1524 0.1524)
			(layers "B.Cu" "B.Mask" "B.Paste")
			(net "P1V8_E")
			(options
				(clearance outline)
				(anchor circle)
			)
			(primitives
				(gr_poly
					(pts
						(arc
							(start 0.3048 0.2032)
							(mid 0.275042 0.275042)
							(end 0.2032 0.3048)
						)
						(arc
							(start -0.2032 0.3048)
							(mid -0.275042 0.275042)
							(end -0.3048 0.2032)
						)
						(arc
							(start -0.3048 -0.2032)
							(mid -0.275042 -0.275042)
							(end -0.2032 -0.3048)
						)
						(arc
							(start 0.2032 -0.3048)
							(mid 0.275042 -0.275042)
							(end 0.3048 -0.2032)
						)
					)
					(width 0)
					(fill yes)
				)
			)
		)
		(pad "2" smd custom
			(at 0 0.4445 270)
			(size 0.1524 0.1524)
			(layers "B.Cu" "B.Mask" "B.Paste")
			(net "GND")
			(options
				(clearance outline)
				(anchor circle)
			)
			(primitives
				(gr_poly
					(pts
						(arc
							(start 0.3048 0.2032)
							(mid 0.275042 0.275042)
							(end 0.2032 0.3048)
						)
						(arc
							(start -0.2032 0.3048)
							(mid -0.275042 0.275042)
							(end -0.3048 0.2032)
						)
						(arc
							(start -0.3048 -0.2032)
							(mid -0.275042 -0.275042)
							(end -0.2032 -0.3048)
						)
						(arc
							(start 0.2032 -0.3048)
							(mid 0.275042 -0.275042)
							(end 0.3048 -0.2032)
						)
					)
					(width 0)
					(fill yes)
				)
			)
		)
	)
	(footprint ""
		(layer "B.Cu")
		(at 91.04376 -48.0822)
		(property "Reference" "STP9"
			(at 0 0 0)
			(layer "B.SilkS")
			(hide yes)
			(effects
				(font
					(size 1.27 1.27)
				)
				(justify mirror)
			)
		)
		(property "Value" "TPAD28"
			(at -0.0127 -1.8034 0)
			(unlocked yes)
			(layer "B.Fab")
			(hide yes)
			(effects
				(font
					(size 1.016 1.016)
					(thickness 0.1524)
				)
				(justify mirror)
			)
		)
		(property "Device Type" "TPAD28"
			(at -0.0127 -3.3274 0)
			(unlocked yes)
			(layer "B.Fab")
			(hide yes)
			(effects
				(font
					(size 1.016 1.016)
					(thickness 0.1524)
				)
				(justify mirror)
			)
		)
		(duplicate_pad_numbers_are_jumpers no)
		(fp_poly
			(pts
				(arc
					(start 0.3556 0)
					(mid -0.3556 0)
					(end 0.3556 0)
				)
			)
			(stroke
				(width 0)
				(type default)
			)
			(fill no)
			(layer "B.CrtYd")
		)
		(fp_poly
			(pts
				(arc
					(start 0.6096 0)
					(mid -0.6096 0)
					(end 0.6096 0)
				)
			)
			(stroke
				(width 0)
				(type default)
			)
			(fill no)
			(layer "B.Fab")
		)
		(pad "1" smd circle
			(at 0 0 180)
			(size 0.7112 0.7112)
			(layers "B.Cu" "B.Mask" "B.Paste")
			(net "SIO_LOAD_0")
		)
	)
)
